(kicad_pcb
	(version 20260206)
	(generator "pcbnew")
	(generator_version "10.0")
	(general
		(thickness 1.6)
		(legacy_teardrops no)
	)
	(paper "A4")
	(title_block
		(title "04192023_DAF0TMB3IC0_F0TG_MB_C_brd_V02_OCP.brd")
		(comment 1 "Grand Teton / footprints 7358-7364 of 8354")
	)
	(layers
		(0 "F.Cu" signal "TOP")
		(4 "In1.Cu" signal "GND")
		(6 "In2.Cu" signal "IN1")
		(8 "In3.Cu" signal "GND1")
		(10 "In4.Cu" signal "IN2")
		(12 "In5.Cu" signal "GND2")
		(14 "In6.Cu" signal "IN3")
		(16 "In7.Cu" signal "GND3")
		(18 "In8.Cu" signal "VCC")
		(20 "In9.Cu" signal "VCC1")
		(22 "In10.Cu" signal "GND4")
		(24 "In11.Cu" signal "IN4")
		(26 "In12.Cu" signal "GND5")
		(28 "In13.Cu" signal "IN5")
		(30 "In14.Cu" signal "GND6")
		(32 "In15.Cu" signal "IN6")
		(34 "In16.Cu" signal "GND7")
		(2 "B.Cu" signal "BOTTOM")
		(9 "F.Adhes" user "F.Adhesive")
		(11 "B.Adhes" user "B.Adhesive")
		(13 "F.Paste" user "Package Geometry/Pastemask Top")
		(15 "B.Paste" user "Package Geometry/Pastemask Bottom")
		(5 "F.SilkS" user "Ref Des/Silkscreen Top")
		(7 "B.SilkS" user "Ref Des/Silkscreen Bottom")
		(1 "F.Mask" user "Board Geometry/Soldermask Top")
		(3 "B.Mask" user "Board Geometry/Soldermask Bottom")
		(17 "Dwgs.User" user "User.Drawings")
		(19 "Cmts.User" user "User.Comments")
		(21 "Eco1.User" user "User.Eco1")
		(23 "Eco2.User" user "User.Eco2")
		(25 "Edge.Cuts" user "Board Geometry/Outline")
		(27 "Margin" user)
		(31 "F.CrtYd" user "Package Geometry/Place Bound Top")
		(29 "B.CrtYd" user "Package Geometry/Place Bound Bottom")
		(35 "F.Fab" user "Ref Des/Assembly Top")
		(33 "B.Fab" user "Ref Des/Assembly Bottom")
	)
	(footprint ""
		(layer "B.Cu")
		(at 128.811528 -39.090092 180)
		(property "Reference" "C6072"
			(at 0 0 0)
			(layer "B.SilkS")
			(hide yes)
			(effects
				(font
					(size 1.27 1.27)
				)
				(justify mirror)
			)
		)
		(property "Value" ""
			(at 0 0 0)
			(layer "B.Fab")
			(effects
				(font
					(size 1.27 1.27)
				)
				(justify mirror)
			)
		)
		(duplicate_pad_numbers_are_jumpers no)
		(fp_line
			(start 0.7874 0.4064)
			(end 0.7874 -0.4064)
			(stroke
				(width 0.1524)
				(type default)
			)
			(layer "B.SilkS")
		)
		(fp_line
			(start 0.7874 -0.4064)
			(end -0.7874 -0.4064)
			(stroke
				(width 0.1524)
				(type default)
			)
			(layer "B.SilkS")
		)
		(fp_line
			(start -0.7874 0.4064)
			(end 0.7874 0.4064)
			(stroke
				(width 0.1524)
				(type default)
			)
			(layer "B.SilkS")
		)
		(fp_line
			(start -0.7874 -0.4064)
			(end -0.7874 0.4064)
			(stroke
				(width 0.1524)
				(type default)
			)
			(layer "B.SilkS")
		)
		(fp_line
			(start 0.67945 0.3048)
			(end 0.67945 -0.305054)
			(stroke
				(width 0.1)
				(type default)
			)
			(layer "B.Fab")
		)
		(fp_line
			(start 0.67945 -0.305054)
			(end 0.12065 -0.305054)
			(stroke
				(width 0.1)
				(type default)
			)
			(layer "B.Fab")
		)
		(fp_line
			(start 0.12065 0.3048)
			(end 0.67945 0.3048)
			(stroke
				(width 0.1)
				(type default)
			)
			(layer "B.Fab")
		)
		(fp_line
			(start 0.12065 0.2794)
			(end 0.12065 0.3048)
			(stroke
				(width 0.1)
				(type default)
			)
			(layer "B.Fab")
		)
		(fp_line
			(start 0.12065 -0.2794)
			(end -0.12065 -0.2794)
			(stroke
				(width 0.1)
				(type default)
			)
			(layer "B.Fab")
		)
		(fp_line
			(start 0.12065 -0.305054)
			(end 0.12065 -0.2794)
			(stroke
				(width 0.1)
				(type default)
			)
			(layer "B.Fab")
		)
		(fp_line
			(start -0.120396 0.3048)
			(end -0.120396 0.2794)
			(stroke
				(width 0.1)
				(type default)
			)
			(layer "B.Fab")
		)
		(fp_line
			(start -0.120396 0.2794)
			(end 0.12065 0.2794)
			(stroke
				(width 0.1)
				(type default)
			)
			(layer "B.Fab")
		)
		(fp_line
			(start -0.12065 -0.2794)
			(end -0.12065 -0.3048)
			(stroke
				(width 0.1)
				(type default)
			)
			(layer "B.Fab")
		)
		(fp_line
			(start -0.12065 -0.3048)
			(end -0.67945 -0.3048)
			(stroke
				(width 0.1)
				(type default)
			)
			(layer "B.Fab")
		)
		(fp_line
			(start -0.67945 0.3048)
			(end -0.120396 0.3048)
			(stroke
				(width 0.1)
				(type default)
			)
			(layer "B.Fab")
		)
		(fp_line
			(start -0.67945 -0.3048)
			(end -0.67945 0.3048)
			(stroke
				(width 0.1)
				(type default)
			)
			(layer "B.Fab")
		)
		(pad "1" smd circle
			(at 0.40005 0)
			(size 0 0)
			(layers "B.Cu" "B.Mask" "B.Paste")
			(net "P1V2_AUX")
		)
		(pad "2" smd circle
			(at -0.40005 0)
			(size 0 0)
			(layers "B.Cu" "B.Mask" "B.Paste")
			(net "GND")
		)
	)
	(footprint ""
		(layer "B.Cu")
		(at 95.64624 -388.011162 -90)
		(property "Reference" "C344"
			(at 0 0 90)
			(layer "B.SilkS")
			(hide yes)
			(effects
				(font
					(size 1.27 1.27)
				)
				(justify mirror)
			)
		)
		(property "Value" ""
			(at 0 0 90)
			(layer "B.Fab")
			(effects
				(font
					(size 1.27 1.27)
				)
				(justify mirror)
			)
		)
		(duplicate_pad_numbers_are_jumpers no)
		(fp_line
			(start -0.299974 0.150114)
			(end 0.299974 0.150114)
			(stroke
				(width 0.1)
				(type default)
			)
			(layer "B.Fab")
		)
		(fp_line
			(start 0.299974 0.150114)
			(end 0.299974 -0.150114)
			(stroke
				(width 0.1)
				(type default)
			)
			(layer "B.Fab")
		)
		(fp_line
			(start -0.299974 -0.150114)
			(end -0.299974 0.150114)
			(stroke
				(width 0.1)
				(type default)
			)
			(layer "B.Fab")
		)
		(fp_line
			(start 0.299974 -0.150114)
			(end -0.299974 -0.150114)
			(stroke
				(width 0.1)
				(type default)
			)
			(layer "B.Fab")
		)
		(pad "1" smd rect
			(at 0.2667 0 90)
			(size 0.3048 0.381)
			(layers "B.Cu" "B.Mask" "B.Paste")
			(net "P0V9_CPU1_RT1_2A")
		)
		(pad "2" smd rect
			(at -0.2667 0 90)
			(size 0.3048 0.381)
			(layers "B.Cu" "B.Mask" "B.Paste")
			(net "GND")
		)
	)
	(footprint ""
		(layer "B.Cu")
		(at 32.69615 -192.66027 180)
		(property "Reference" "C182"
			(at 0 0 0)
			(layer "B.SilkS")
			(hide yes)
			(effects
				(font
					(size 1.27 1.27)
				)
				(justify mirror)
			)
		)
		(property "Value" ""
			(at 0 0 0)
			(layer "B.Fab")
			(effects
				(font
					(size 1.27 1.27)
				)
				(justify mirror)
			)
		)
		(duplicate_pad_numbers_are_jumpers no)
		(fp_line
			(start 1.524 0.762)
			(end 1.524 -0.762)
			(stroke
				(width 0.1524)
				(type default)
			)
			(layer "B.SilkS")
		)
		(fp_line
			(start 1.524 -0.762)
			(end -1.524 -0.762)
			(stroke
				(width 0.1524)
				(type default)
			)
			(layer "B.SilkS")
		)
		(fp_line
			(start -1.524 0.762)
			(end 1.524 0.762)
			(stroke
				(width 0.1524)
				(type default)
			)
			(layer "B.SilkS")
		)
		(fp_line
			(start -1.524 -0.762)
			(end -1.524 0.762)
			(stroke
				(width 0.1524)
				(type default)
			)
			(layer "B.SilkS")
		)
		(fp_line
			(start 1.1049 0.724916)
			(end -1.1049 0.724916)
			(stroke
				(width 0.1)
				(type default)
			)
			(layer "B.Fab")
		)
		(fp_line
			(start 1.1049 -0.724916)
			(end 1.1049 0.724916)
			(stroke
				(width 0.1)
				(type default)
			)
			(layer "B.Fab")
		)
		(fp_line
			(start -1.1049 0.724916)
			(end -1.1049 -0.724916)
			(stroke
				(width 0.1)
				(type default)
			)
			(layer "B.Fab")
		)
		(fp_line
			(start -1.1049 -0.724916)
			(end 1.1049 -0.724916)
			(stroke
				(width 0.1)
				(type default)
			)
			(layer "B.Fab")
		)
		(pad "1" smd rect
			(at 0.889 0 180)
			(size 1.016 1.27)
			(layers "B.Cu" "B.Mask" "B.Paste")
			(net "P12V_MEM_CPU1")
		)
		(pad "2" smd rect
			(at -0.889 0 180)
			(size 1.016 1.27)
			(layers "B.Cu" "B.Mask" "B.Paste")
			(net "GND")
		)
	)
	(footprint ""
		(layer "B.Cu")
		(at 408.671776 -141.40942)
		(property "Reference" "PR3337"
			(at 0 0 0)
			(layer "B.SilkS")
			(hide yes)
			(effects
				(font
					(size 1.27 1.27)
				)
				(justify mirror)
			)
		)
		(property "Value" ""
			(at 0 0 0)
			(layer "B.Fab")
			(effects
				(font
					(size 1.27 1.27)
				)
				(justify mirror)
			)
		)
		(duplicate_pad_numbers_are_jumpers no)
		(fp_line
			(start -0.7874 -0.4064)
			(end -0.7874 0.4064)
			(stroke
				(width 0.1524)
				(type default)
			)
			(layer "B.SilkS")
		)
		(fp_line
			(start -0.7874 0.4064)
			(end 0.7874 0.4064)
			(stroke
				(width 0.1524)
				(type default)
			)
			(layer "B.SilkS")
		)
		(fp_line
			(start 0.7874 -0.4064)
			(end -0.7874 -0.4064)
			(stroke
				(width 0.1524)
				(type default)
			)
			(layer "B.SilkS")
		)
		(fp_line
			(start 0.7874 0.4064)
			(end 0.7874 -0.4064)
			(stroke
				(width 0.1524)
				(type default)
			)
			(layer "B.SilkS")
		)
		(fp_line
			(start -0.67945 -0.3048)
			(end -0.67945 0.3048)
			(stroke
				(width 0.1)
				(type default)
			)
			(layer "B.Fab")
		)
		(fp_line
			(start -0.67945 0.3048)
			(end -0.120396 0.3048)
			(stroke
				(width 0.1)
				(type default)
			)
			(layer "B.Fab")
		)
		(fp_line
			(start -0.12065 -0.3048)
			(end -0.67945 -0.3048)
			(stroke
				(width 0.1)
				(type default)
			)
			(layer "B.Fab")
		)
		(fp_line
			(start -0.12065 -0.2794)
			(end -0.12065 -0.3048)
			(stroke
				(width 0.1)
				(type default)
			)
			(layer "B.Fab")
		)
		(fp_line
			(start -0.120396 0.2794)
			(end 0.12065 0.2794)
			(stroke
				(width 0.1)
				(type default)
			)
			(layer "B.Fab")
		)
		(fp_line
			(start -0.120396 0.3048)
			(end -0.120396 0.2794)
			(stroke
				(width 0.1)
				(type default)
			)
			(layer "B.Fab")
		)
		(fp_line
			(start 0.12065 -0.305054)
			(end 0.12065 -0.2794)
			(stroke
				(width 0.1)
				(type default)
			)
			(layer "B.Fab")
		)
		(fp_line
			(start 0.12065 -0.2794)
			(end -0.12065 -0.2794)
			(stroke
				(width 0.1)
				(type default)
			)
			(layer "B.Fab")
		)
		(fp_line
			(start 0.12065 0.2794)
			(end 0.12065 0.3048)
			(stroke
				(width 0.1)
				(type default)
			)
			(layer "B.Fab")
		)
		(fp_line
			(start 0.12065 0.3048)
			(end 0.67945 0.3048)
			(stroke
				(width 0.1)
				(type default)
			)
			(layer "B.Fab")
		)
		(fp_line
			(start 0.67945 -0.305054)
			(end 0.12065 -0.305054)
			(stroke
				(width 0.1)
				(type default)
			)
			(layer "B.Fab")
		)
		(fp_line
			(start 0.67945 0.3048)
			(end 0.67945 -0.305054)
			(stroke
				(width 0.1)
				(type default)
			)
			(layer "B.Fab")
		)
		(pad "1" smd circle
			(at 0.40005 0 180)
			(size 0 0)
			(layers "B.Cu" "B.Mask" "B.Paste")
			(net "P5V_AUX_MODE")
		)
		(pad "2" smd circle
			(at -0.40005 0 180)
			(size 0 0)
			(layers "B.Cu" "B.Mask" "B.Paste")
			(net "GND")
		)
	)
	(footprint ""
		(layer "B.Cu")
		(at 428.211742 -194.88531 180)
		(property "Reference" "R766"
			(at 0 0 0)
			(layer "B.SilkS")
			(hide yes)
			(effects
				(font
					(size 1.27 1.27)
				)
				(justify mirror)
			)
		)
		(property "Value" ""
			(at 0 0 0)
			(layer "B.Fab")
			(effects
				(font
					(size 1.27 1.27)
				)
				(justify mirror)
			)
		)
		(duplicate_pad_numbers_are_jumpers no)
		(fp_line
			(start 0.7874 0.4064)
			(end 0.7874 -0.4064)
			(stroke
				(width 0.1524)
				(type default)
			)
			(layer "B.SilkS")
		)
		(fp_line
			(start 0.7874 -0.4064)
			(end -0.7874 -0.4064)
			(stroke
				(width 0.1524)
				(type default)
			)
			(layer "B.SilkS")
		)
		(fp_line
			(start -0.7874 0.4064)
			(end 0.7874 0.4064)
			(stroke
				(width 0.1524)
				(type default)
			)
			(layer "B.SilkS")
		)
		(fp_line
			(start -0.7874 -0.4064)
			(end -0.7874 0.4064)
			(stroke
				(width 0.1524)
				(type default)
			)
			(layer "B.SilkS")
		)
		(fp_line
			(start 0.67945 0.3048)
			(end 0.67945 -0.305054)
			(stroke
				(width 0.1)
				(type default)
			)
			(layer "B.Fab")
		)
		(fp_line
			(start 0.67945 -0.305054)
			(end 0.12065 -0.305054)
			(stroke
				(width 0.1)
				(type default)
			)
			(layer "B.Fab")
		)
		(fp_line
			(start 0.12065 0.3048)
			(end 0.67945 0.3048)
			(stroke
				(width 0.1)
				(type default)
			)
			(layer "B.Fab")
		)
		(fp_line
			(start 0.12065 0.2794)
			(end 0.12065 0.3048)
			(stroke
				(width 0.1)
				(type default)
			)
			(layer "B.Fab")
		)
		(fp_line
			(start 0.12065 -0.2794)
			(end -0.12065 -0.2794)
			(stroke
				(width 0.1)
				(type default)
			)
			(layer "B.Fab")
		)
		(fp_line
			(start 0.12065 -0.305054)
			(end 0.12065 -0.2794)
			(stroke
				(width 0.1)
				(type default)
			)
			(layer "B.Fab")
		)
		(fp_line
			(start -0.120396 0.3048)
			(end -0.120396 0.2794)
			(stroke
				(width 0.1)
				(type default)
			)
			(layer "B.Fab")
		)
		(fp_line
			(start -0.120396 0.2794)
			(end 0.12065 0.2794)
			(stroke
				(width 0.1)
				(type default)
			)
			(layer "B.Fab")
		)
		(fp_line
			(start -0.12065 -0.2794)
			(end -0.12065 -0.3048)
			(stroke
				(width 0.1)
				(type default)
			)
			(layer "B.Fab")
		)
		(fp_line
			(start -0.12065 -0.3048)
			(end -0.67945 -0.3048)
			(stroke
				(width 0.1)
				(type default)
			)
			(layer "B.Fab")
		)
		(fp_line
			(start -0.67945 0.3048)
			(end -0.120396 0.3048)
			(stroke
				(width 0.1)
				(type default)
			)
			(layer "B.Fab")
		)
		(fp_line
			(start -0.67945 -0.3048)
			(end -0.67945 0.3048)
			(stroke
				(width 0.1)
				(type default)
			)
			(layer "B.Fab")
		)
		(pad "1" smd circle
			(at 0.40005 0)
			(size 0 0)
			(layers "B.Cu" "B.Mask" "B.Paste")
			(net "PD_CHI_CPU0_DIMM_SAA")
		)
		(pad "2" smd circle
			(at -0.40005 0)
			(size 0 0)
			(layers "B.Cu" "B.Mask" "B.Paste")
			(net "GND")
		)
	)
	(footprint ""
		(layer "B.Cu")
		(at 232.857802 -251.042678 -90)
		(property "Reference" "C11"
			(at 0 0 90)
			(layer "B.SilkS")
			(hide yes)
			(effects
				(font
					(size 1.27 1.27)
				)
				(justify mirror)
			)
		)
		(property "Value" ""
			(at 0 0 90)
			(layer "B.Fab")
			(effects
				(font
					(size 1.27 1.27)
				)
				(justify mirror)
			)
		)
		(duplicate_pad_numbers_are_jumpers no)
		(fp_line
			(start -0.7874 0.4064)
			(end 0.7874 0.4064)
			(stroke
				(width 0.1524)
				(type default)
			)
			(layer "B.SilkS")
		)
		(fp_line
			(start 0.7874 0.4064)
			(end 0.7874 -0.4064)
			(stroke
				(width 0.1524)
				(type default)
			)
			(layer "B.SilkS")
		)
		(fp_line
			(start -0.7874 -0.4064)
			(end -0.7874 0.4064)
			(stroke
				(width 0.1524)
				(type default)
			)
			(layer "B.SilkS")
		)
		(fp_line
			(start 0.7874 -0.4064)
			(end -0.7874 -0.4064)
			(stroke
				(width 0.1524)
				(type default)
			)
			(layer "B.SilkS")
		)
		(fp_line
			(start -0.67945 0.3048)
			(end -0.120396 0.3048)
			(stroke
				(width 0.1)
				(type default)
			)
			(layer "B.Fab")
		)
		(fp_line
			(start -0.120396 0.3048)
			(end -0.120396 0.2794)
			(stroke
				(width 0.1)
				(type default)
			)
			(layer "B.Fab")
		)
		(fp_line
			(start 0.12065 0.3048)
			(end 0.67945 0.3048)
			(stroke
				(width 0.1)
				(type default)
			)
			(layer "B.Fab")
		)
		(fp_line
			(start 0.67945 0.3048)
			(end 0.67945 -0.305054)
			(stroke
				(width 0.1)
				(type default)
			)
			(layer "B.Fab")
		)
		(fp_line
			(start -0.120396 0.2794)
			(end 0.12065 0.2794)
			(stroke
				(width 0.1)
				(type default)
			)
			(layer "B.Fab")
		)
		(fp_line
			(start 0.12065 0.2794)
			(end 0.12065 0.3048)
			(stroke
				(width 0.1)
				(type default)
			)
			(layer "B.Fab")
		)
		(fp_line
			(start -0.12065 -0.2794)
			(end -0.12065 -0.3048)
			(stroke
				(width 0.1)
				(type default)
			)
			(layer "B.Fab")
		)
		(fp_line
			(start 0.12065 -0.2794)
			(end -0.12065 -0.2794)
			(stroke
				(width 0.1)
				(type default)
			)
			(layer "B.Fab")
		)
		(fp_line
			(start -0.67945 -0.3048)
			(end -0.67945 0.3048)
			(stroke
				(width 0.1)
				(type default)
			)
			(layer "B.Fab")
		)
		(fp_line
			(start -0.12065 -0.3048)
			(end -0.67945 -0.3048)
			(stroke
				(width 0.1)
				(type default)
			)
			(layer "B.Fab")
		)
		(fp_line
			(start 0.12065 -0.305054)
			(end 0.12065 -0.2794)
			(stroke
				(width 0.1)
				(type default)
			)
			(layer "B.Fab")
		)
		(fp_line
			(start 0.67945 -0.305054)
			(end 0.12065 -0.305054)
			(stroke
				(width 0.1)
				(type default)
			)
			(layer "B.Fab")
		)
		(pad "1" smd circle
			(at 0.40005 0 90)
			(size 0 0)
			(layers "B.Cu" "B.Mask" "B.Paste")
			(net "P3V3_AUX")
		)
		(pad "2" smd circle
			(at -0.40005 0 90)
			(size 0 0)
			(layers "B.Cu" "B.Mask" "B.Paste")
			(net "GND")
		)
	)
	(footprint ""
		(layer "B.Cu")
		(at 233.553 -240.411 -90)
		(property "Reference" "R359"
			(at 0 0 90)
			(layer "B.SilkS")
			(hide yes)
			(effects
				(font
					(size 1.27 1.27)
				)
				(justify mirror)
			)
		)
		(property "Value" ""
			(at 0 0 90)
			(layer "B.Fab")
			(effects
				(font
					(size 1.27 1.27)
				)
				(justify mirror)
			)
		)
		(duplicate_pad_numbers_are_jumpers no)
		(fp_line
			(start -0.7874 0.4064)
			(end 0.7874 0.4064)
			(stroke
				(width 0.1524)
				(type default)
			)
			(layer "B.SilkS")
		)
		(fp_line
			(start 0.7874 0.4064)
			(end 0.7874 -0.4064)
			(stroke
				(width 0.1524)
				(type default)
			)
			(layer "B.SilkS")
		)
		(fp_line
			(start -0.7874 -0.4064)
			(end -0.7874 0.4064)
			(stroke
				(width 0.1524)
				(type default)
			)
			(layer "B.SilkS")
		)
		(fp_line
			(start 0.7874 -0.4064)
			(end -0.7874 -0.4064)
			(stroke
				(width 0.1524)
				(type default)
			)
			(layer "B.SilkS")
		)
		(fp_line
			(start -0.67945 0.3048)
			(end -0.120396 0.3048)
			(stroke
				(width 0.1)
				(type default)
			)
			(layer "B.Fab")
		)
		(fp_line
			(start -0.120396 0.3048)
			(end -0.120396 0.2794)
			(stroke
				(width 0.1)
				(type default)
			)
			(layer "B.Fab")
		)
		(fp_line
			(start 0.12065 0.3048)
			(end 0.67945 0.3048)
			(stroke
				(width 0.1)
				(type default)
			)
			(layer "B.Fab")
		)
		(fp_line
			(start 0.67945 0.3048)
			(end 0.67945 -0.305054)
			(stroke
				(width 0.1)
				(type default)
			)
			(layer "B.Fab")
		)
		(fp_line
			(start -0.120396 0.2794)
			(end 0.12065 0.2794)
			(stroke
				(width 0.1)
				(type default)
			)
			(layer "B.Fab")
		)
		(fp_line
			(start 0.12065 0.2794)
			(end 0.12065 0.3048)
			(stroke
				(width 0.1)
				(type default)
			)
			(layer "B.Fab")
		)
		(fp_line
			(start -0.12065 -0.2794)
			(end -0.12065 -0.3048)
			(stroke
				(width 0.1)
				(type default)
			)
			(layer "B.Fab")
		)
		(fp_line
			(start 0.12065 -0.2794)
			(end -0.12065 -0.2794)
			(stroke
				(width 0.1)
				(type default)
			)
			(layer "B.Fab")
		)
		(fp_line
			(start -0.67945 -0.3048)
			(end -0.67945 0.3048)
			(stroke
				(width 0.1)
				(type default)
			)
			(layer "B.Fab")
		)
		(fp_line
			(start -0.12065 -0.3048)
			(end -0.67945 -0.3048)
			(stroke
				(width 0.1)
				(type default)
			)
			(layer "B.Fab")
		)
		(fp_line
			(start 0.12065 -0.305054)
			(end 0.12065 -0.2794)
			(stroke
				(width 0.1)
				(type default)
			)
			(layer "B.Fab")
		)
		(fp_line
			(start 0.67945 -0.305054)
			(end 0.12065 -0.305054)
			(stroke
				(width 0.1)
				(type default)
			)
			(layer "B.Fab")
		)
		(pad "1" smd circle
			(at 0.40005 0 90)
			(size 0 0)
			(layers "B.Cu" "B.Mask" "B.Paste")
			(net "PVDD11_S3_P1")
		)
		(pad "2" smd circle
			(at -0.40005 0 90)
			(size 0 0)
			(layers "B.Cu" "B.Mask" "B.Paste")
			(net "SMB_APML_CPU1_SDA")
		)
	)
)
